# SCM (Grand Teton) — schematic netlist excerpt (pin names and nets, part order shuffled) for the footprints in the layout excerpt that follows; sources: Cadence DE-HDL packaged netlist, KiCad conversion of 12092022_DA0F0TMDCD0_F0T_Management_Board_D_brd_V3_OCP.brd

U14  AP22811AW57  AP22811AW5-7 IC  pkg SOT25-5_0-95_3X1-6  page 52
  \out\  = P3V3_RGM
  GND  = GND
  \flg#\  = TP_U14_FLAG_N
  EN  = EN_P3V3_RGM_R
  \in\  = P3V3_AUX

R673  Q_RES  0 5% CHIP  pkg 0402LF  page 29 : A = USB3_01_MUX_FB_TXP ; B = USB3_01_FB_TXP

(kicad_pcb
	(version 20260206)
	(generator "pcbnew")
	(generator_version "10.0")
	(general
		(thickness 1.6)
		(legacy_teardrops no)
	)
	(paper "A4")
	(title_block
		(title "12092022_DA0F0TMDCD0_F0T_Management_Board_D_brd_V3_OCP.brd")
		(comment 1 "Grand Teton / footprints 520-521 of 1440")
	)
	(layers
		(0 "F.Cu" signal "TOP")
		(4 "In1.Cu" signal "GND")
		(6 "In2.Cu" signal "IN1")
		(8 "In3.Cu" signal "GND1")
		(10 "In4.Cu" signal "IN2")
		(12 "In5.Cu" signal "VCC")
		(14 "In6.Cu" signal "VCC1")
		(16 "In7.Cu" signal "IN3")
		(18 "In8.Cu" signal "GND2")
		(20 "In9.Cu" signal "IN4")
		(22 "In10.Cu" signal "GND3")
		(2 "B.Cu" signal "BOTTOM")
		(9 "F.Adhes" user "F.Adhesive")
		(11 "B.Adhes" user "B.Adhesive")
		(13 "F.Paste" user "Package Geometry/Pastemask Top")
		(15 "B.Paste" user "Package Geometry/Pastemask Bottom")
		(5 "F.SilkS" user "Ref Des/Silkscreen Top")
		(7 "B.SilkS" user "Ref Des/Silkscreen Bottom")
		(1 "F.Mask" user "Board Geometry/Soldermask Top")
		(3 "B.Mask" user "Board Geometry/Soldermask Bottom")
		(17 "Dwgs.User" user "User.Drawings")
		(19 "Cmts.User" user "User.Comments")
		(21 "Eco1.User" user "User.Eco1")
		(23 "Eco2.User" user "User.Eco2")
		(25 "Edge.Cuts" user "Board Geometry/Outline")
		(27 "Margin" user)
		(31 "F.CrtYd" user "Package Geometry/Place Bound Top")
		(29 "B.CrtYd" user "Package Geometry/Place Bound Bottom")
		(35 "F.Fab" user "Ref Des/Assembly Top")
		(33 "B.Fab" user "Ref Des/Assembly Bottom")
	)
	(footprint ""
		(layer "F.Cu")
		(at 40.556942 -22.15642 -90)
		(property "Reference" "R673"
			(at 0 0 270)
			(layer "F.SilkS")
			(hide yes)
			(effects
				(font
					(size 1.27 1.27)
				)
			)
		)
		(property "Value" ""
			(at 0 0 270)
			(layer "F.Fab")
			(effects
				(font
					(size 1.27 1.27)
				)
			)
		)
		(duplicate_pad_numbers_are_jumpers no)
		(fp_line
			(start 0.7874 0.4064)
			(end -0.7874 0.4064)
			(stroke
				(width 0.1524)
				(type default)
			)
			(layer "F.SilkS")
		)
		(fp_line
			(start -0.7874 -0.4064)
			(end 0.7874 -0.4064)
			(stroke
				(width 0.1524)
				(type default)
			)
			(layer "F.SilkS")
		)
		(fp_line
			(start -0.67945 0.3048)
			(end -0.67945 -0.305054)
			(stroke
				(width 0.1)
				(type default)
			)
			(layer "F.Fab")
		)
		(fp_line
			(start -0.12065 0.3048)
			(end -0.67945 0.3048)
			(stroke
				(width 0.1)
				(type default)
			)
			(layer "F.Fab")
		)
		(fp_line
			(start 0.120396 0.3048)
			(end 0.120396 0.2794)
			(stroke
				(width 0.1)
				(type default)
			)
			(layer "F.Fab")
		)
		(fp_line
			(start 0.67945 0.3048)
			(end 0.120396 0.3048)
			(stroke
				(width 0.1)
				(type default)
			)
			(layer "F.Fab")
		)
		(fp_line
			(start -0.12065 0.2794)
			(end -0.12065 0.3048)
			(stroke
				(width 0.1)
				(type default)
			)
			(layer "F.Fab")
		)
		(fp_line
			(start 0.120396 0.2794)
			(end -0.12065 0.2794)
			(stroke
				(width 0.1)
				(type default)
			)
			(layer "F.Fab")
		)
		(fp_line
			(start -0.12065 -0.2794)
			(end 0.12065 -0.2794)
			(stroke
				(width 0.1)
				(type default)
			)
			(layer "F.Fab")
		)
		(fp_line
			(start 0.12065 -0.2794)
			(end 0.12065 -0.3048)
			(stroke
				(width 0.1)
				(type default)
			)
			(layer "F.Fab")
		)
		(fp_line
			(start 0.12065 -0.3048)
			(end 0.67945 -0.3048)
			(stroke
				(width 0.1)
				(type default)
			)
			(layer "F.Fab")
		)
		(fp_line
			(start 0.67945 -0.3048)
			(end 0.67945 0.3048)
			(stroke
				(width 0.1)
				(type default)
			)
			(layer "F.Fab")
		)
		(fp_line
			(start -0.67945 -0.305054)
			(end -0.12065 -0.305054)
			(stroke
				(width 0.1)
				(type default)
			)
			(layer "F.Fab")
		)
		(fp_line
			(start -0.12065 -0.305054)
			(end -0.12065 -0.2794)
			(stroke
				(width 0.1)
				(type default)
			)
			(layer "F.Fab")
		)
		(pad "1" smd circle
			(at -0.40005 0 270)
			(size 0 0)
			(layers "F.Cu" "F.Mask" "F.Paste")
			(net "USB3_01_MUX_FB_TXP")
		)
		(pad "2" smd circle
			(at 0.40005 0 270)
			(size 0 0)
			(layers "F.Cu" "F.Mask" "F.Paste")
			(net "USB3_01_FB_TXP")
		)
	)
	(footprint ""
		(layer "F.Cu")
		(at 67.900804 -31.191454 -90)
		(property "Reference" "U14"
			(at -2.019046 0.754634 90)
			(unlocked yes)
			(layer "F.SilkS")
			(effects
				(font
					(size 0.7874 0.5842)
					(thickness 0.1524)
				)
				(justify left)
			)
		)
		(property "Value" ""
			(at 0 0 270)
			(layer "F.Fab")
			(effects
				(font
					(size 1.27 1.27)
				)
			)
		)
		(duplicate_pad_numbers_are_jumpers no)
		(fp_line
			(start -1.733296 1.549908)
			(end 1.733296 1.549908)
			(stroke
				(width 0.1524)
				(type default)
			)
			(layer "F.SilkS")
		)
		(fp_line
			(start 1.733296 1.549908)
			(end 1.733296 -1.549908)
			(stroke
				(width 0.1524)
				(type default)
			)
			(layer "F.SilkS")
		)
		(fp_line
			(start 0 -0.889)
			(end -0.660908 -1.549908)
			(stroke
				(width 0.1524)
				(type default)
			)
			(layer "F.SilkS")
		)
		(fp_line
			(start -1.733296 -1.549908)
			(end -1.733296 1.549908)
			(stroke
				(width 0.1524)
				(type default)
			)
			(layer "F.SilkS")
		)
		(fp_line
			(start -0.660908 -1.549908)
			(end -1.733296 -1.549908)
			(stroke
				(width 0.1524)
				(type default)
			)
			(layer "F.SilkS")
		)
		(fp_line
			(start 0.660908 -1.549908)
			(end 0 -0.889)
			(stroke
				(width 0.1524)
				(type default)
			)
			(layer "F.SilkS")
		)
		(fp_line
			(start 1.733296 -1.549908)
			(end 0.660908 -1.549908)
			(stroke
				(width 0.1524)
				(type default)
			)
			(layer "F.SilkS")
		)
		(fp_poly
			(pts
				(xy -2.4384 -1.20396) (xy -2.4384 -0.69596) (xy -1.9304 -0.94996)
			)
			(stroke
				(width 0)
				(type default)
			)
			(fill yes)
			(layer "F.SilkS")
		)
		(fp_line
			(start -0.849884 1.549908)
			(end 0.849884 1.549908)
			(stroke
				(width 0.1)
				(type default)
			)
			(layer "F.Fab")
		)
		(fp_line
			(start 0.849884 1.549908)
			(end 0.849884 -1.549908)
			(stroke
				(width 0.1)
				(type default)
			)
			(layer "F.Fab")
		)
		(fp_line
			(start -0.849884 -1.549908)
			(end -0.849884 1.549908)
			(stroke
				(width 0.1)
				(type default)
			)
			(layer "F.Fab")
		)
		(fp_line
			(start 0.849884 -1.549908)
			(end -0.849884 -1.549908)
			(stroke
				(width 0.1)
				(type default)
			)
			(layer "F.Fab")
		)
		(fp_poly
			(pts
				(xy -2.4384 -1.20396) (xy -2.4384 -0.69596) (xy -1.9304 -0.94996)
			)
			(stroke
				(width 0)
				(type default)
			)
			(fill yes)
			(layer "F.Fab")
		)
		(pad "1" smd rect
			(at -1.199896 -0.94996 180)
			(size 0.5588 0.8128)
			(layers "F.Cu" "F.Mask" "F.Paste")
			(net "P3V3_RGM")
		)
		(pad "2" smd rect
			(at -1.199896 0 180)
			(size 0.5588 0.8128)
			(layers "F.Cu" "F.Mask" "F.Paste")
			(net "GND")
		)
		(pad "3" smd rect
			(at -1.199896 0.94996 180)
			(size 0.5588 0.8128)
			(layers "F.Cu" "F.Mask" "F.Paste")
			(net "TP_U14_FLAG_N")
		)
		(pad "4" smd rect
			(at 1.199896 0.94996 180)
			(size 0.5588 0.8128)
			(layers "F.Cu" "F.Mask" "F.Paste")
			(net "EN_P3V3_RGM_R")
		)
		(pad "5" smd rect
			(at 1.199896 -0.94996 180)
			(size 0.5588 0.8128)
			(layers "F.Cu" "F.Mask" "F.Paste")
			(net "P3V3_AUX")
		)
	)
)
